(kicad_pcb
	(version 20260206)
	(generator "pcbnew")
	(generator_version "10.0")
	(general
		(thickness 1.6)
		(legacy_teardrops no)
	)
	(paper "A4")
	(title_block
		(title "Bryce Canyon_R.DPB_16317-1_OCP.brd")
		(comment 1 "Bryce Canyon / footprints 37-39 of 2099")
	)
	(layers
		(0 "F.Cu" signal "TOP")
		(4 "In1.Cu" signal "L2GND")
		(6 "In2.Cu" signal "L3")
		(8 "In3.Cu" signal "L4VCC")
		(10 "In4.Cu" signal "L5VCC")
		(12 "In5.Cu" signal "L6")
		(14 "In6.Cu" signal "L7GND")
		(2 "B.Cu" signal "BOTTOM")
		(9 "F.Adhes" user "F.Adhesive")
		(11 "B.Adhes" user "B.Adhesive")
		(13 "F.Paste" user "Package Geometry/Pastemask Top")
		(15 "B.Paste" user "Package Geometry/Pastemask Bottom")
		(5 "F.SilkS" user "Ref Des/Silkscreen Top")
		(7 "B.SilkS" user "Ref Des/Silkscreen Bottom")
		(1 "F.Mask" user "Board Geometry/Soldermask Top")
		(3 "B.Mask" user "Board Geometry/Soldermask Bottom")
		(17 "Dwgs.User" user "User.Drawings")
		(19 "Cmts.User" user "User.Comments")
		(21 "Eco1.User" user "User.Eco1")
		(23 "Eco2.User" user "User.Eco2")
		(25 "Edge.Cuts" user "Board Geometry/Outline")
		(27 "Margin" user)
		(31 "F.CrtYd" user "Package Geometry/Place Bound Top")
		(29 "B.CrtYd" user "Package Geometry/Place Bound Bottom")
		(35 "F.Fab" user "Ref Des/Assembly Top")
		(33 "B.Fab" user "Ref Des/Assembly Bottom")
	)
	(footprint ""
		(layer "F.Cu")
		(at 149.1996 -133.4516 -90)
		(property "Reference" "R446"
			(at 0 0 270)
			(layer "F.SilkS")
			(hide yes)
			(effects
				(font
					(size 1.27 1.27)
				)
			)
		)
		(property "Value" "1KR2F-3-GP"
			(at 0.064008 -3.993896 270)
			(unlocked yes)
			(layer "F.Fab")
			(hide yes)
			(effects
				(font
					(size 1.016 1.016)
					(thickness 0.1524)
				)
			)
		)
		(property "Device Type" "R402H16"
			(at 0.064008 -5.517896 270)
			(unlocked yes)
			(layer "F.Fab")
			(hide yes)
			(effects
				(font
					(size 1.016 1.016)
					(thickness 0.1524)
				)
			)
		)
		(duplicate_pad_numbers_are_jumpers no)
		(fp_line
			(start -0.508 -0.9398)
			(end -0.508 0.9398)
			(stroke
				(width 0.1524)
				(type default)
			)
			(layer "F.SilkS")
		)
		(fp_line
			(start 0.508 -0.9398)
			(end -0.508 -0.9398)
			(stroke
				(width 0.1524)
				(type default)
			)
			(layer "F.SilkS")
		)
		(fp_rect
			(start -0.508 0.9398)
			(end 0.508 -0.9398)
			(stroke
				(width 0)
				(type default)
			)
			(fill no)
			(layer "F.CrtYd")
		)
		(fp_rect
			(start -0.508 0.9398)
			(end 0.508 -0.9398)
			(stroke
				(width 0)
				(type default)
			)
			(fill no)
			(layer "F.Fab")
		)
		(pad "1" smd custom
			(at 0 -0.4445 270)
			(size 0.1397 0.1397)
			(layers "F.Cu" "F.Mask" "F.Paste")
			(net "P3V3_STBY_B")
			(options
				(clearance outline)
				(anchor circle)
			)
			(primitives
				(gr_poly
					(pts
						(arc
							(start -0.1778 -0.2794)
							(mid -0.249642 -0.249642)
							(end -0.2794 -0.1778)
						)
						(arc
							(start -0.2794 0.1778)
							(mid -0.249642 0.249642)
							(end -0.1778 0.2794)
						)
						(arc
							(start 0.1778 0.2794)
							(mid 0.249642 0.249642)
							(end 0.2794 0.1778)
						)
						(arc
							(start 0.2794 -0.1778)
							(mid 0.249642 -0.249642)
							(end 0.1778 -0.2794)
						)
					)
					(width 0)
					(fill yes)
				)
			)
		)
		(pad "2" smd custom
			(at 0 0.4445 270)
			(size 0.1397 0.1397)
			(layers "F.Cu" "F.Mask" "F.Paste")
			(net "SW_PWR_R_HDD16")
			(options
				(clearance outline)
				(anchor circle)
			)
			(primitives
				(gr_poly
					(pts
						(arc
							(start -0.1778 -0.2794)
							(mid -0.249642 -0.249642)
							(end -0.2794 -0.1778)
						)
						(arc
							(start -0.2794 0.1778)
							(mid -0.249642 0.249642)
							(end -0.1778 0.2794)
						)
						(arc
							(start 0.1778 0.2794)
							(mid 0.249642 0.249642)
							(end 0.2794 0.1778)
						)
						(arc
							(start 0.2794 -0.1778)
							(mid 0.249642 -0.249642)
							(end 0.1778 -0.2794)
						)
					)
					(width 0)
					(fill yes)
				)
			)
		)
	)
	(footprint ""
		(layer "F.Cu")
		(at 435.269386 -120.651778 -90)
		(property "Reference" "R1168"
			(at 0 0 270)
			(layer "F.SilkS")
			(hide yes)
			(effects
				(font
					(size 1.27 1.27)
				)
			)
		)
		(property "Value" "143KR2F-L-1-GP"
			(at 0.064008 -3.993896 270)
			(unlocked yes)
			(layer "F.Fab")
			(hide yes)
			(effects
				(font
					(size 1.016 1.016)
					(thickness 0.1524)
				)
			)
		)
		(property "Device Type" "R402H16"
			(at 0.064008 -5.517896 270)
			(unlocked yes)
			(layer "F.Fab")
			(hide yes)
			(effects
				(font
					(size 1.016 1.016)
					(thickness 0.1524)
				)
			)
		)
		(duplicate_pad_numbers_are_jumpers no)
		(fp_line
			(start -0.508 -0.9398)
			(end -0.508 0.9398)
			(stroke
				(width 0.1524)
				(type default)
			)
			(layer "F.SilkS")
		)
		(fp_line
			(start 0.508 -0.9398)
			(end -0.508 -0.9398)
			(stroke
				(width 0.1524)
				(type default)
			)
			(layer "F.SilkS")
		)
		(fp_rect
			(start -0.508 0.9398)
			(end 0.508 -0.9398)
			(stroke
				(width 0)
				(type default)
			)
			(fill no)
			(layer "F.CrtYd")
		)
		(fp_rect
			(start -0.508 0.9398)
			(end 0.508 -0.9398)
			(stroke
				(width 0)
				(type default)
			)
			(fill no)
			(layer "F.Fab")
		)
		(pad "1" smd custom
			(at 0 -0.4445 270)
			(size 0.1397 0.1397)
			(layers "F.Cu" "F.Mask" "F.Paste")
			(net "AGND_P5V_B_4")
			(options
				(clearance outline)
				(anchor circle)
			)
			(primitives
				(gr_poly
					(pts
						(arc
							(start -0.1778 -0.2794)
							(mid -0.249642 -0.249642)
							(end -0.2794 -0.1778)
						)
						(arc
							(start -0.2794 0.1778)
							(mid -0.249642 0.249642)
							(end -0.1778 0.2794)
						)
						(arc
							(start 0.1778 0.2794)
							(mid 0.249642 0.249642)
							(end 0.2794 0.1778)
						)
						(arc
							(start 0.2794 -0.1778)
							(mid 0.249642 -0.249642)
							(end 0.1778 -0.2794)
						)
					)
					(width 0)
					(fill yes)
				)
			)
		)
		(pad "2" smd custom
			(at 0 0.4445 270)
			(size 0.1397 0.1397)
			(layers "F.Cu" "F.Mask" "F.Paste")
			(net "P5V_B_4_TRIP")
			(options
				(clearance outline)
				(anchor circle)
			)
			(primitives
				(gr_poly
					(pts
						(arc
							(start -0.1778 -0.2794)
							(mid -0.249642 -0.249642)
							(end -0.2794 -0.1778)
						)
						(arc
							(start -0.2794 0.1778)
							(mid -0.249642 0.249642)
							(end -0.1778 0.2794)
						)
						(arc
							(start 0.1778 0.2794)
							(mid 0.249642 0.249642)
							(end 0.2794 0.1778)
						)
						(arc
							(start 0.2794 -0.1778)
							(mid 0.249642 -0.249642)
							(end 0.1778 -0.2794)
						)
					)
					(width 0)
					(fill yes)
				)
			)
		)
	)
	(footprint ""
		(layer "F.Cu")
		(at 451.749922 -143.91005 -90)
		(property "Reference" "HDDSAS22"
			(at 0 0 270)
			(layer "F.SilkS")
			(hide yes)
			(effects
				(font
					(size 1.27 1.27)
				)
			)
		)
		(property "Value" "SKT-SAS15P-14P-45-GP"
			(at -20.7645 -8.9789 270)
			(unlocked yes)
			(layer "F.Fab")
			(hide yes)
			(effects
				(font
					(size 1.016 1.016)
					(thickness 0.1524)
				)
			)
		)
		(property "Device Type" "10120818-001C-TRLF"
			(at -20.7645 -10.5029 270)
			(unlocked yes)
			(layer "F.Fab")
			(hide yes)
			(effects
				(font
					(size 1.016 1.016)
					(thickness 0.1524)
				)
			)
		)
		(duplicate_pad_numbers_are_jumpers no)
		(fp_line
			(start 1.651 4.2926)
			(end 1.651 3.0099)
			(stroke
				(width 0.1524)
				(type default)
			)
			(layer "F.SilkS")
		)
		(fp_line
			(start 8.509 4.2926)
			(end 1.651 4.2926)
			(stroke
				(width 0.1524)
				(type default)
			)
			(layer "F.SilkS")
		)
		(fp_line
			(start -23.4188 3.0099)
			(end -23.4188 -3.2512)
			(stroke
				(width 0.1524)
				(type default)
			)
			(layer "F.SilkS")
		)
		(fp_line
			(start 1.651 3.0099)
			(end -23.4188 3.0099)
			(stroke
				(width 0.1524)
				(type default)
			)
			(layer "F.SilkS")
		)
		(fp_line
			(start 8.509 3.0099)
			(end 8.509 4.2926)
			(stroke
				(width 0.1524)
				(type default)
			)
			(layer "F.SilkS")
		)
		(fp_line
			(start 23.4188 3.0099)
			(end 8.509 3.0099)
			(stroke
				(width 0.1524)
				(type default)
			)
			(layer "F.SilkS")
		)
		(fp_line
			(start -23.4188 -3.2512)
			(end 23.4188 -3.2512)
			(stroke
				(width 0.1524)
				(type default)
			)
			(layer "F.SilkS")
		)
		(fp_line
			(start 23.4188 -3.2512)
			(end 23.4188 3.0099)
			(stroke
				(width 0.1524)
				(type default)
			)
			(layer "F.SilkS")
		)
		(fp_line
			(start 15.5067 -3.3401)
			(end 16.2687 -3.3401)
			(stroke
				(width 0.3302)
				(type default)
			)
			(layer "F.SilkS")
		)
		(fp_poly
			(pts
				(xy 15.868904 -3.230372) (xy 16.503904 -3.865372) (xy 15.233904 -3.865372)
			)
			(stroke
				(width 0)
				(type default)
			)
			(fill yes)
			(layer "F.SilkS")
		)
		(fp_poly
			(pts
				(xy -22.8727 -2.7559) (xy 22.8727 -2.7559) (xy 22.8727 2.7559) (xy 8.255 2.7559) (xy 8.255 3.5179)
				(xy 1.905 3.5179) (xy 1.905 2.7559) (xy -22.8727 2.7559)
			)
			(stroke
				(width 0)
				(type default)
			)
			(fill no)
			(layer "F.CrtYd")
		)
		(fp_poly
			(pts
				(xy 1.397 4.5466) (xy 1.397 3.2639) (xy -23.6728 3.2639) (xy -23.6728 -3.5052) (xy 23.6728 -3.5052)
				(xy 23.6728 -0.00635) (xy 22.8727 -0.00635) (xy 22.8727 -2.7559) (xy -22.8727 -2.7559) (xy -22.8727 2.7559)
				(xy 1.905 2.7559) (xy 1.905 3.5179) (xy 8.255 3.5179) (xy 8.255 2.7559) (xy 22.8727 2.7559) (xy 22.8727 0.00635)
				(xy 23.6728 0.00635) (xy 23.6728 3.2639) (xy 8.763 3.2639) (xy 8.763 4.5466)
			)
			(stroke
				(width 0)
				(type default)
			)
			(fill no)
			(layer "F.CrtYd")
		)
		(fp_poly
			(pts
				(xy 1.397 4.5466) (xy 1.397 3.2639) (xy -23.6728 3.2639) (xy -23.6728 -3.5052) (xy 23.6728 -3.5052)
				(xy 23.6728 3.2639) (xy 8.763 3.2639) (xy 8.763 4.5466)
			)
			(stroke
				(width 0)
				(type default)
			)
			(fill no)
			(layer "F.Fab")
		)
		(pad "" np_thru_hole circle
			(at -18.874994 0 270)
			(size 0.254 0.254)
			(drill 1.3462)
			(layers "*.Cu" "*.Mask")
			(clearance 0.9017)
			(thermal_gap 0.9017)
		)
		(pad "" np_thru_hole circle
			(at 18.874994 0 270)
			(size 0.254 0.254)
			(drill 0.9398)
			(layers "*.Cu" "*.Mask")
			(clearance 0.6985)
			(thermal_gap 0.6985)
		)
		(pad "G1" smd rect
			(at 21.874988 0 270)
			(size 2.5908 2.5908)
			(layers "F.Cu" "F.Mask" "F.Paste")
			(net "GND")
		)
		(pad "G2" smd rect
			(at -21.874988 0 270)
			(size 2.5908 2.5908)
			(layers "F.Cu" "F.Mask" "F.Paste")
			(net "GND")
		)
		(pad "P1" smd rect
			(at 1.905 -1.82499 270)
			(size 0.6096 2.3622)
			(layers "F.Cu" "F.Mask" "F.Paste")
			(net "Net_1689")
		)
		(pad "P2" smd rect
			(at 0.635 -1.82499 270)
			(size 0.6096 2.3622)
			(layers "F.Cu" "F.Mask" "F.Paste")
			(net "Net_1690")
		)
		(pad "P3" smd rect
			(at -0.635 -1.82499 270)
			(size 0.6096 2.3622)
			(layers "F.Cu" "F.Mask" "F.Paste")
			(net "Net_1691")
		)
		(pad "P4" smd rect
			(at -1.905 -1.82499 270)
			(size 0.6096 2.3622)
			(layers "F.Cu" "F.Mask" "F.Paste")
			(net "GND")
		)
		(pad "P5" smd rect
			(at -3.175 -1.82499 270)
			(size 0.6096 2.3622)
			(layers "F.Cu" "F.Mask" "F.Paste")
			(net "HDD_PRSNT_22")
		)
		(pad "P6" smd rect
			(at -4.445 -1.82499 270)
			(size 0.6096 2.3622)
			(layers "F.Cu" "F.Mask" "F.Paste")
			(net "GND")
		)
		(pad "P7" smd rect
			(at -5.715 -1.82499 270)
			(size 0.6096 2.3622)
			(layers "F.Cu" "F.Mask" "F.Paste")
			(net "5V_PRE_22")
		)
		(pad "P8" smd rect
			(at -6.985 -1.82499 270)
			(size 0.6096 2.3622)
			(layers "F.Cu" "F.Mask" "F.Paste")
			(net "P5V_HDD22")
		)
		(pad "P9" smd rect
			(at -8.255 -1.82499 270)
			(size 0.6096 2.3622)
			(layers "F.Cu" "F.Mask" "F.Paste")
			(net "P5V_HDD22")
		)
		(pad "P10" smd rect
			(at -9.525 -1.82499 270)
			(size 0.6096 2.3622)
			(layers "F.Cu" "F.Mask" "F.Paste")
			(net "GND")
		)
		(pad "P11" smd rect
			(at -10.795 -1.82499 270)
			(size 0.6096 2.3622)
			(layers "F.Cu" "F.Mask" "F.Paste")
			(net "ACT_HDD_22")
		)
		(pad "P12" smd rect
			(at -12.065 -1.82499 270)
			(size 0.6096 2.3622)
			(layers "F.Cu" "F.Mask" "F.Paste")
			(net "GND")
		)
		(pad "P13" smd rect
			(at -13.335 -1.82499 270)
			(size 0.6096 2.3622)
			(layers "F.Cu" "F.Mask" "F.Paste")
			(net "12V_PRE_22")
		)
		(pad "P14" smd rect
			(at -14.605 -1.82499 270)
			(size 0.6096 2.3622)
			(layers "F.Cu" "F.Mask" "F.Paste")
			(net "P12V_HDD22")
		)
		(pad "P15" smd rect
			(at -15.875 -1.82499 270)
			(size 0.6096 2.3622)
			(layers "F.Cu" "F.Mask" "F.Paste")
			(net "P12V_HDD22")
		)
		(pad "S1" smd rect
			(at 15.875 -1.82499 270)
			(size 0.6096 2.3622)
			(layers "F.Cu" "F.Mask" "F.Paste")
			(net "GND")
		)
		(pad "S2" smd rect
			(at 14.605 -1.82499 270)
			(size 0.6096 2.3622)
			(layers "F.Cu" "F.Mask" "F.Paste")
			(net "SAS_HDD_RX_P22")
		)
		(pad "S3" smd rect
			(at 13.335 -1.82499 270)
			(size 0.6096 2.3622)
			(layers "F.Cu" "F.Mask" "F.Paste")
			(net "SAS_HDD_RX_N22")
		)
		(pad "S4" smd rect
			(at 12.065 -1.82499 270)
			(size 0.6096 2.3622)
			(layers "F.Cu" "F.Mask" "F.Paste")
			(net "GND")
		)
		(pad "S5" smd rect
			(at 10.795 -1.82499 270)
			(size 0.6096 2.3622)
			(layers "F.Cu" "F.Mask" "F.Paste")
			(net "PHY_DRV_B_TO_SCC_B_22_DN")
		)
		(pad "S6" smd rect
			(at 9.525 -1.82499 270)
			(size 0.6096 2.3622)
			(layers "F.Cu" "F.Mask" "F.Paste")
			(net "PHY_DRV_B_TO_SCC_B_22_DP")
		)
		(pad "S7" smd rect
			(at 8.255 -1.82499 270)
			(size 0.6096 2.3622)
			(layers "F.Cu" "F.Mask" "F.Paste")
			(net "GND")
		)
		(pad "S8" smd rect
			(at 7.480046 2.845054 270)
			(size 0.508 2.3622)
			(layers "F.Cu" "F.Mask" "F.Paste")
			(net "GND")
		)
		(pad "S9" smd rect
			(at 6.679946 2.845054 270)
			(size 0.508 2.3622)
			(layers "F.Cu" "F.Mask" "F.Paste")
			(net "Net_446")
		)
		(pad "S10" smd rect
			(at 5.8801 2.845054 270)
			(size 0.508 2.3622)
			(layers "F.Cu" "F.Mask" "F.Paste")
			(net "Net_338")
		)
		(pad "S11" smd rect
			(at 5.08 2.845054 270)
			(size 0.508 2.3622)
			(layers "F.Cu" "F.Mask" "F.Paste")
			(net "GND")
		)
		(pad "S12" smd rect
			(at 4.2799 2.845054 270)
			(size 0.508 2.3622)
			(layers "F.Cu" "F.Mask" "F.Paste")
			(net "Net_374")
		)
		(pad "S13" smd rect
			(at 3.480054 2.845054 270)
			(size 0.508 2.3622)
			(layers "F.Cu" "F.Mask" "F.Paste")
			(net "Net_410")
		)
		(pad "S14" smd rect
			(at 2.679954 2.845054 270)
			(size 0.508 2.3622)
			(layers "F.Cu" "F.Mask" "F.Paste")
			(net "GND")
		)
		(zone
			(layer "F.Cu")
			(hatch none 0.5)
			(connect_pads
				(clearance 0)
			)
			(min_thickness 0.25)
			(keepout
				(tracks allowed)
				(vias not_allowed)
				(pads allowed)
				(copperpour not_allowed)
				(footprints allowed)
			)
			(placement
				(enabled no)
				(sheetname "")
			)
			(fill
				(thermal_gap 0.5)
				(thermal_bridge_width 0.5)
				(island_removal_mode 0)
			)
			(polygon
				(pts
					(xy 455.407522 -160.64865) (xy 448.333622 -160.64865) (xy 448.333622 -167.58285) (xy 449.438522 -167.58285)
					(xy 449.438522 -163.46805) (xy 454.061322 -163.46805) (xy 454.061322 -167.58285) (xy 455.407522 -167.58285)
				)
			)
		)
		(zone
			(layer "F.Cu")
			(hatch none 0.5)
			(connect_pads
				(clearance 0)
			)
			(min_thickness 0.25)
			(keepout
				(tracks not_allowed)
				(vias allowed)
				(pads allowed)
				(copperpour not_allowed)
				(footprints allowed)
			)
			(placement
				(enabled no)
				(sheetname "")
			)
			(fill
				(thermal_gap 0.5)
				(thermal_bridge_width 0.5)
				(island_removal_mode 0)
			)
			(polygon
				(pts
					(xy 455.407522 -160.64865) (xy 448.333622 -160.64865) (xy 448.333622 -167.58285) (xy 449.438522 -167.58285)
					(xy 449.438522 -163.46805) (xy 454.061322 -163.46805) (xy 454.061322 -167.58285) (xy 455.407522 -167.58285)
				)
			)
		)
		(zone
			(layer "F.Cu")
			(hatch none 0.5)
			(connect_pads
				(clearance 0)
			)
			(min_thickness 0.25)
			(keepout
				(tracks not_allowed)
				(vias allowed)
				(pads allowed)
				(copperpour not_allowed)
				(footprints allowed)
			)
			(placement
				(enabled no)
				(sheetname "")
			)
			(fill
				(thermal_gap 0.5)
				(thermal_bridge_width 0.5)
				(island_removal_mode 0)
			)
			(polygon
				(pts
					(xy 455.407522 -127.17145) (xy 448.333622 -127.17145) (xy 448.333622 -120.23725) (xy 449.438522 -120.23725)
					(xy 449.438522 -124.35205) (xy 454.061322 -124.35205) (xy 454.061322 -120.23725) (xy 455.407522 -120.23725)
				)
			)
		)
		(zone
			(layer "F.Cu")
			(hatch none 0.5)
			(connect_pads
				(clearance 0)
			)
			(min_thickness 0.25)
			(keepout
				(tracks allowed)
				(vias not_allowed)
				(pads allowed)
				(copperpour not_allowed)
				(footprints allowed)
			)
			(placement
				(enabled no)
				(sheetname "")
			)
			(fill
				(thermal_gap 0.5)
				(thermal_bridge_width 0.5)
				(island_removal_mode 0)
			)
			(polygon
				(pts
					(xy 455.407522 -127.17145) (xy 448.333622 -127.17145) (xy 448.333622 -120.23725) (xy 449.438522 -120.23725)
					(xy 449.438522 -124.35205) (xy 454.061322 -124.35205) (xy 454.061322 -120.23725) (xy 455.407522 -120.23725)
				)
			)
		)
		(zone
			(layers "F.Cu" "B.Cu" "In1.Cu" "In2.Cu" "In3.Cu" "In4.Cu" "In5.Cu" "In6.Cu")
			(hatch none 0.5)
			(connect_pads
				(clearance 0)
			)
			(min_thickness 0.25)
			(keepout
				(tracks not_allowed)
				(vias allowed)
				(pads allowed)
				(copperpour not_allowed)
				(footprints allowed)
			)
			(placement
				(enabled no)
				(sheetname "")
			)
			(fill
				(thermal_gap 0.5)
				(thermal_bridge_width 0.5)
				(island_removal_mode 0)
			)
			(polygon
				(pts
					(arc
						(start 452.524622 -125.035056)
						(mid 450.975222 -125.035056)
						(end 452.524622 -125.035056)
					)
				)
			)
		)
		(zone
			(layers "F.Cu" "B.Cu" "In1.Cu" "In2.Cu" "In3.Cu" "In4.Cu" "In5.Cu" "In6.Cu")
			(hatch none 0.5)
			(connect_pads
				(clearance 0)
			)
			(min_thickness 0.25)
			(keepout
				(tracks not_allowed)
				(vias allowed)
				(pads allowed)
				(copperpour not_allowed)
				(footprints allowed)
			)
			(placement
				(enabled no)
				(sheetname "")
			)
			(fill
				(thermal_gap 0.5)
				(thermal_bridge_width 0.5)
				(island_removal_mode 0)
			)
			(polygon
				(pts
					(arc
						(start 452.727822 -162.785044)
						(mid 450.772022 -162.785044)
						(end 452.727822 -162.785044)
					)
				)
			)
		)
	)
)
